# S9S_MB_2U (Grand Teton) — schematic netlist excerpt (pin names and nets, part order shuffled) for the footprints in the layout excerpt that follows; sources: Cadence DE-HDL packaged netlist, KiCad conversion of 03242023_DA0F0TMBIJ0_F0T_Motherboard_J_brd_V01_OCP.brd

R1297  Q_RES  0 5% CHIP  pkg 0402LF  page 197 : A = PECI_BMC_R ; B = PECI_BMC_B1

U245  NC7SB3157  NC7SB3157P6X EMPTY  pkg SMLF  page 165
  B1  = OCP_V3_2_NOT_PRSNT_RBT_ARB_IN
  GND  = GND
  B0  = OCP_V3_2_RBT_ARB_IN
  A  = OCP_SFF_RBT_ARB_IN_MUX2_R
  VCC  = P3V3_AUX
  S  = OCP_V3_2_PRSNT_ALL_R3_N

(kicad_pcb
	(version 20260206)
	(generator "pcbnew")
	(generator_version "10.0")
	(general
		(thickness 1.6)
		(legacy_teardrops no)
	)
	(paper "A4")
	(title_block
		(title "03242023_DA0F0TMBIJ0_F0T_Motherboard_J_brd_V01_OCP.brd")
		(comment 1 "Grand Teton / footprints 27-28 of 6105")
	)
	(layers
		(0 "F.Cu" signal "TOP")
		(4 "In1.Cu" signal "GND")
		(6 "In2.Cu" signal "IN1")
		(8 "In3.Cu" signal "GND1")
		(10 "In4.Cu" signal "IN2")
		(12 "In5.Cu" signal "GND2")
		(14 "In6.Cu" signal "IN3")
		(16 "In7.Cu" signal "GND3")
		(18 "In8.Cu" signal "VCC")
		(20 "In9.Cu" signal "VCC1")
		(22 "In10.Cu" signal "GND4")
		(24 "In11.Cu" signal "IN4")
		(26 "In12.Cu" signal "GND5")
		(28 "In13.Cu" signal "IN5")
		(30 "In14.Cu" signal "GND6")
		(32 "In15.Cu" signal "IN6")
		(34 "In16.Cu" signal "GND7")
		(2 "B.Cu" signal "BOTTOM")
		(9 "F.Adhes" user "F.Adhesive")
		(11 "B.Adhes" user "B.Adhesive")
		(13 "F.Paste" user "Package Geometry/Pastemask Top")
		(15 "B.Paste" user "Package Geometry/Pastemask Bottom")
		(5 "F.SilkS" user "Ref Des/Silkscreen Top")
		(7 "B.SilkS" user "Ref Des/Silkscreen Bottom")
		(1 "F.Mask" user "Board Geometry/Soldermask Top")
		(3 "B.Mask" user "Board Geometry/Soldermask Bottom")
		(17 "Dwgs.User" user "User.Drawings")
		(19 "Cmts.User" user "User.Comments")
		(21 "Eco1.User" user "User.Eco1")
		(23 "Eco2.User" user "User.Eco2")
		(25 "Edge.Cuts" user "Board Geometry/Outline")
		(27 "Margin" user)
		(31 "F.CrtYd" user "Package Geometry/Place Bound Top")
		(29 "B.CrtYd" user "Package Geometry/Place Bound Bottom")
		(35 "F.Fab" user "Ref Des/Assembly Top")
		(33 "B.Fab" user "Ref Des/Assembly Bottom")
	)
	(footprint ""
		(layer "F.Cu")
		(at 136.00684 -33.477708)
		(property "Reference" "U245"
			(at -1.64084 2.55143 0)
			(unlocked yes)
			(layer "F.SilkS")
			(effects
				(font
					(size 0.7874 0.5842)
					(thickness 0.1524)
				)
			)
		)
		(property "Value" ""
			(at 0 0 0)
			(layer "F.Fab")
			(effects
				(font
					(size 1.27 1.27)
				)
			)
		)
		(duplicate_pad_numbers_are_jumpers no)
		(fp_line
			(start -1.7272 1.1176)
			(end -1.7272 -1.1176)
			(stroke
				(width 0.1524)
				(type default)
			)
			(layer "F.SilkS")
		)
		(fp_line
			(start -0.254 -1.1176)
			(end -1.7272 -1.1176)
			(stroke
				(width 0.1524)
				(type default)
			)
			(layer "F.SilkS")
		)
		(fp_line
			(start 0 -0.7366)
			(end -0.254 -1.1176)
			(stroke
				(width 0.1524)
				(type default)
			)
			(layer "F.SilkS")
		)
		(fp_line
			(start 0.254 -1.1176)
			(end 0 -0.7366)
			(stroke
				(width 0.1524)
				(type default)
			)
			(layer "F.SilkS")
		)
		(fp_line
			(start 1.7272 -1.1176)
			(end 0.254 -1.1176)
			(stroke
				(width 0.1524)
				(type default)
			)
			(layer "F.SilkS")
		)
		(fp_line
			(start 1.7272 -1.1176)
			(end 1.7272 1.1176)
			(stroke
				(width 0.1524)
				(type default)
			)
			(layer "F.SilkS")
		)
		(fp_line
			(start 1.7272 1.1176)
			(end -1.7272 1.1176)
			(stroke
				(width 0.1524)
				(type default)
			)
			(layer "F.SilkS")
		)
		(fp_poly
			(pts
				(xy -2.7178 -0.268986) (xy -2.7178 -1.030986) (xy -1.9558 -0.649986)
			)
			(stroke
				(width 0)
				(type default)
			)
			(fill yes)
			(layer "F.SilkS")
		)
		(fp_line
			(start -1.5748 -1.1176)
			(end -1.5748 1.1176)
			(stroke
				(width 0.1)
				(type default)
			)
			(layer "F.Fab")
		)
		(fp_line
			(start -1.5748 1.1176)
			(end 1.5748 1.1176)
			(stroke
				(width 0.1)
				(type default)
			)
			(layer "F.Fab")
		)
		(fp_line
			(start 1.5748 -1.1176)
			(end -1.5748 -1.1176)
			(stroke
				(width 0.1)
				(type default)
			)
			(layer "F.Fab")
		)
		(fp_line
			(start 1.5748 1.1176)
			(end 1.5748 -1.1176)
			(stroke
				(width 0.1)
				(type default)
			)
			(layer "F.Fab")
		)
		(fp_poly
			(pts
				(xy -1.9558 -0.649986) (xy -2.7178 -0.268986) (xy -2.7178 -1.030986)
			)
			(stroke
				(width 0)
				(type default)
			)
			(fill yes)
			(layer "F.Fab")
		)
		(pad "1" smd rect
			(at -0.999998 -0.649986 270)
			(size 0.3556 1.1176)
			(layers "F.Cu" "F.Mask" "F.Paste")
			(net "OCP_V3_2_NOT_PRSNT_RBT_ARB_IN")
		)
		(pad "2" smd rect
			(at -0.999998 0 270)
			(size 0.3556 1.1176)
			(layers "F.Cu" "F.Mask" "F.Paste")
			(net "GND")
		)
		(pad "3" smd rect
			(at -0.999998 0.649986 270)
			(size 0.3556 1.1176)
			(layers "F.Cu" "F.Mask" "F.Paste")
			(net "OCP_V3_2_RBT_ARB_IN")
		)
		(pad "4" smd rect
			(at 0.999998 0.649986 270)
			(size 0.3556 1.1176)
			(layers "F.Cu" "F.Mask" "F.Paste")
			(net "OCP_SFF_RBT_ARB_IN_MUX2_R")
		)
		(pad "5" smd rect
			(at 0.999998 0 270)
			(size 0.3556 1.1176)
			(layers "F.Cu" "F.Mask" "F.Paste")
			(net "P3V3_AUX")
		)
		(pad "6" smd rect
			(at 0.999998 -0.649986 270)
			(size 0.3556 1.1176)
			(layers "F.Cu" "F.Mask" "F.Paste")
			(net "OCP_V3_2_PRSNT_ALL_R3_N")
		)
	)
	(footprint ""
		(layer "F.Cu")
		(at 306.71262 -56.020208 90)
		(property "Reference" "R1297"
			(at 0 0 90)
			(layer "F.SilkS")
			(hide yes)
			(effects
				(font
					(size 1.27 1.27)
				)
			)
		)
		(property "Value" ""
			(at 0 0 90)
			(layer "F.Fab")
			(effects
				(font
					(size 1.27 1.27)
				)
			)
		)
		(duplicate_pad_numbers_are_jumpers no)
		(fp_line
			(start 0.7874 -0.4064)
			(end 0.7874 0.4064)
			(stroke
				(width 0.1524)
				(type default)
			)
			(layer "F.SilkS")
		)
		(fp_line
			(start -0.7874 -0.4064)
			(end 0.7874 -0.4064)
			(stroke
				(width 0.1524)
				(type default)
			)
			(layer "F.SilkS")
		)
		(fp_line
			(start 0.7874 0.4064)
			(end -0.7874 0.4064)
			(stroke
				(width 0.1524)
				(type default)
			)
			(layer "F.SilkS")
		)
		(fp_line
			(start -0.7874 0.4064)
			(end -0.7874 -0.4064)
			(stroke
				(width 0.1524)
				(type default)
			)
			(layer "F.SilkS")
		)
		(fp_line
			(start -0.12065 -0.305054)
			(end -0.12065 -0.2794)
			(stroke
				(width 0.1)
				(type default)
			)
			(layer "F.Fab")
		)
		(fp_line
			(start -0.67945 -0.305054)
			(end -0.12065 -0.305054)
			(stroke
				(width 0.1)
				(type default)
			)
			(layer "F.Fab")
		)
		(fp_line
			(start 0.67945 -0.3048)
			(end 0.67945 0.3048)
			(stroke
				(width 0.1)
				(type default)
			)
			(layer "F.Fab")
		)
		(fp_line
			(start 0.12065 -0.3048)
			(end 0.67945 -0.3048)
			(stroke
				(width 0.1)
				(type default)
			)
			(layer "F.Fab")
		)
		(fp_line
			(start 0.12065 -0.2794)
			(end 0.12065 -0.3048)
			(stroke
				(width 0.1)
				(type default)
			)
			(layer "F.Fab")
		)
		(fp_line
			(start -0.12065 -0.2794)
			(end 0.12065 -0.2794)
			(stroke
				(width 0.1)
				(type default)
			)
			(layer "F.Fab")
		)
		(fp_line
			(start 0.120396 0.2794)
			(end -0.12065 0.2794)
			(stroke
				(width 0.1)
				(type default)
			)
			(layer "F.Fab")
		)
		(fp_line
			(start -0.12065 0.2794)
			(end -0.12065 0.3048)
			(stroke
				(width 0.1)
				(type default)
			)
			(layer "F.Fab")
		)
		(fp_line
			(start 0.67945 0.3048)
			(end 0.120396 0.3048)
			(stroke
				(width 0.1)
				(type default)
			)
			(layer "F.Fab")
		)
		(fp_line
			(start 0.120396 0.3048)
			(end 0.120396 0.2794)
			(stroke
				(width 0.1)
				(type default)
			)
			(layer "F.Fab")
		)
		(fp_line
			(start -0.12065 0.3048)
			(end -0.67945 0.3048)
			(stroke
				(width 0.1)
				(type default)
			)
			(layer "F.Fab")
		)
		(fp_line
			(start -0.67945 0.3048)
			(end -0.67945 -0.305054)
			(stroke
				(width 0.1)
				(type default)
			)
			(layer "F.Fab")
		)
		(pad "1" smd circle
			(at -0.40005 0 90)
			(size 0 0)
			(layers "F.Cu" "F.Mask" "F.Paste")
			(net "PECI_BMC_R")
		)
		(pad "2" smd circle
			(at 0.40005 0 90)
			(size 0 0)
			(layers "F.Cu" "F.Mask" "F.Paste")
			(net "PECI_BMC_B1")
		)
	)
)
